(kicad_pcb
	(version 20241229)
	(generator "pcbnew")
	(generator_version "9.0")
	(general
		(thickness 1.711)
		(legacy_teardrops no)
	)
	(paper "A4")
	(title_block
		(title "Antmicro Baseboard for Jetson AGX Thor")
		(date "2026-02-18")
		(rev "1.1.0")
		(company "Antmicro Ltd")
		(comment 1 "www.antmicro.com")
		(comment 9 "footprints 65-67 of 1170")
	)
	(layers
		(0 "F.Cu" signal)
		(4 "In1.Cu" signal)
		(6 "In2.Cu" signal)
		(8 "In3.Cu" signal)
		(10 "In4.Cu" jumper)
		(12 "In5.Cu" signal)
		(14 "In6.Cu" signal)
		(16 "In7.Cu" signal)
		(18 "In8.Cu" signal)
		(2 "B.Cu" signal)
		(9 "F.Adhes" user "F.Adhesive")
		(11 "B.Adhes" user "B.Adhesive")
		(13 "F.Paste" user)
		(15 "B.Paste" user)
		(5 "F.SilkS" user "F.Silkscreen")
		(7 "B.SilkS" user "B.Silkscreen")
		(1 "F.Mask" user)
		(3 "B.Mask" user)
		(17 "Dwgs.User" user "User.Drawings")
		(19 "Cmts.User" user "User.Comments")
		(21 "Eco1.User" user "User.Eco1")
		(23 "Eco2.User" user "User.Eco2")
		(25 "Edge.Cuts" user)
		(27 "Margin" user)
		(31 "F.CrtYd" user "F.Courtyard")
		(29 "B.CrtYd" user "B.Courtyard")
		(35 "F.Fab" user)
		(33 "B.Fab" user)
	)
	(footprint "antmicro-footprints:C_0402_1005Metric"
		(layer "F.Cu")
		(at 184.05 110.15 -90)
		(descr "Capacitor SMD 0402")
		(tags "capacitor SMD 0402")
		(property "Reference" "C52"
			(at -1.527 -0.522 90)
			(layer "F.SilkS")
			(effects
				(font
					(size 0.7 0.7)
					(thickness 0.15)
				)
				(justify right top)
			)
		)
		(property "Value" "C_1u_0402"
			(at -1.022927 2.155213 90)
			(layer "F.Fab")
			(effects
				(font
					(size 0.7 0.7)
					(thickness 0.15)
				)
				(justify right top)
			)
		)
		(property "Datasheet" "https://product.tdk.com/en/search/capacitor/ceramic/mlcc/info?part_no=C1005X6S1A105K050BC"
			(at 0 0 90)
			(layer "F.Fab")
			(hide yes)
			(effects
				(font
					(size 1.27 1.27)
					(thickness 0.15)
				)
			)
		)
		(property "Description" "SMD Multilayer Ceramic Capacitor, 1 µF, 10 V, 0402 [1005 Metric], ± 10%, X6S, C"
			(at 0 0 90)
			(layer "F.Fab")
			(hide yes)
			(effects
				(font
					(size 1.27 1.27)
					(thickness 0.15)
				)
			)
		)
		(property "Manufacturer" "TDK"
			(at 0 0 270)
			(unlocked yes)
			(layer "F.Fab")
			(hide yes)
			(effects
				(font
					(size 1 1)
					(thickness 0.15)
				)
			)
		)
		(property "MPN" "C1005X6S1A105K050BC"
			(at 0 0 270)
			(unlocked yes)
			(layer "F.Fab")
			(hide yes)
			(effects
				(font
					(size 1 1)
					(thickness 0.15)
				)
			)
		)
		(property "Val" "1u"
			(at 0 0 270)
			(unlocked yes)
			(layer "F.Fab")
			(hide yes)
			(effects
				(font
					(size 1 1)
					(thickness 0.15)
				)
			)
		)
		(property "License" "Apache-2.0"
			(at 0 0 270)
			(unlocked yes)
			(layer "F.Fab")
			(hide yes)
			(effects
				(font
					(size 1 1)
					(thickness 0.15)
				)
			)
		)
		(property "Author" "Antmicro"
			(at 0 0 270)
			(unlocked yes)
			(layer "F.Fab")
			(hide yes)
			(effects
				(font
					(size 1 1)
					(thickness 0.15)
				)
			)
		)
		(property "Voltage" ""
			(at 0 0 270)
			(unlocked yes)
			(layer "F.Fab")
			(hide yes)
			(effects
				(font
					(size 1 1)
					(thickness 0.15)
				)
			)
		)
		(property "Dielectric" ""
			(at 0 0 270)
			(unlocked yes)
			(layer "F.Fab")
			(hide yes)
			(effects
				(font
					(size 1 1)
					(thickness 0.15)
				)
			)
		)
		(sheetname "/DCDC/")
		(sheetfile "dcdc.kicad_sch")
		(attr smd)
		(fp_rect
			(start -0.925 -0.47)
			(end 0.925 0.47)
			(stroke
				(width 0.05)
				(type default)
			)
			(fill no)
			(layer "F.CrtYd")
		)
		(fp_line
			(start -0.494 0.248)
			(end -0.494 -0.25)
			(stroke
				(width 0.15)
				(type solid)
			)
			(layer "F.Fab")
		)
		(fp_line
			(start 0.504 0.248)
			(end -0.494 0.248)
			(stroke
				(width 0.15)
				(type solid)
			)
			(layer "F.Fab")
		)
		(fp_line
			(start -0.494 -0.25)
			(end 0.504 -0.25)
			(stroke
				(width 0.15)
				(type solid)
			)
			(layer "F.Fab")
		)
		(fp_line
			(start 0.504 -0.25)
			(end 0.504 0.248)
			(stroke
				(width 0.15)
				(type solid)
			)
			(layer "F.Fab")
		)
		(fp_text user "License: Apache-2.0"
			(at -0.939 5.799 90)
			(layer "F.Fab")
			(effects
				(font
					(size 0.7 0.7)
					(thickness 0.15)
				)
				(justify right top)
			)
		)
		(fp_text user "Author: Antmicro"
			(at -0.939 3.399 90)
			(layer "F.Fab")
			(effects
				(font
					(size 0.7 0.7)
					(thickness 0.15)
				)
				(justify right top)
			)
		)
		(fp_text user "${REFERENCE}"
			(at -0.939 4.599 90)
			(layer "F.Fab")
			(effects
				(font
					(size 0.7 0.7)
					(thickness 0.15)
				)
				(justify right top)
			)
		)
		(pad "1" smd roundrect
			(at -0.48 0 270)
			(size 0.59 0.64)
			(layers "F.Cu" "F.Mask" "F.Paste")
			(roundrect_rratio 0.25)
			(net 1 "GND")
			(pintype "passive")
		)
		(pad "2" smd roundrect
			(at 0.48 0 270)
			(size 0.59 0.64)
			(layers "F.Cu" "F.Mask" "F.Paste")
			(roundrect_rratio 0.25)
			(net 18 "/DCDC/5V_VDD")
			(pintype "passive")
		)
	)
	(footprint "antmicro-footprints:C_0805_2012Metric"
		(layer "F.Cu")
		(at 175 79.81 90)
		(descr "Capacitor SMD 0805")
		(tags "capacitor SMD 0805")
		(property "Reference" "C302"
			(at -4.67 0.4 90)
			(layer "F.SilkS")
			(effects
				(font
					(size 0.7 0.7)
					(thickness 0.15)
				)
				(justify left bottom)
			)
		)
		(property "Value" "C_22u_25V_0805"
			(at -2.055717 1.963152 90)
			(layer "F.Fab")
			(effects
				(font
					(size 0.7 0.7)
					(thickness 0.15)
				)
				(justify left bottom)
			)
		)
		(property "Datasheet" "https://product.samsungsem.com/mlcc/CL21A226MAYNNN.do"
			(at 0 0 90)
			(layer "F.Fab")
			(hide yes)
			(effects
				(font
					(size 1.27 1.27)
					(thickness 0.15)
				)
			)
		)
		(property "Description" "SMT Multilayer Ceramic Capacitor, 22uF, +/-20%, 25V, X5R, 0805 [2012 Metric]"
			(at 0 0 90)
			(layer "F.Fab")
			(hide yes)
			(effects
				(font
					(size 1.27 1.27)
					(thickness 0.15)
				)
			)
		)
		(property "MPN" "CL21A226MAYNNNE"
			(at 0 0 90)
			(unlocked yes)
			(layer "F.Fab")
			(hide yes)
			(effects
				(font
					(size 1 1)
					(thickness 0.15)
				)
			)
		)
		(property "Manufacturer" "Samsung Electro-Mechanics"
			(at 0 0 90)
			(unlocked yes)
			(layer "F.Fab")
			(hide yes)
			(effects
				(font
					(size 1 1)
					(thickness 0.15)
				)
			)
		)
		(property "License" "Apache-2.0"
			(at 0 0 90)
			(unlocked yes)
			(layer "F.Fab")
			(hide yes)
			(effects
				(font
					(size 1 1)
					(thickness 0.15)
				)
			)
		)
		(property "Author" "Antmicro"
			(at 0 0 90)
			(unlocked yes)
			(layer "F.Fab")
			(hide yes)
			(effects
				(font
					(size 1 1)
					(thickness 0.15)
				)
			)
		)
		(property "Val" "22u"
			(at 0 0 90)
			(unlocked yes)
			(layer "F.Fab")
			(hide yes)
			(effects
				(font
					(size 1 1)
					(thickness 0.15)
				)
			)
		)
		(property "Voltage" "25V"
			(at 0 0 90)
			(unlocked yes)
			(layer "F.Fab")
			(hide yes)
			(effects
				(font
					(size 1 1)
					(thickness 0.15)
				)
			)
		)
		(property "Dielectric" "X5R"
			(at 0 0 90)
			(unlocked yes)
			(layer "F.Fab")
			(hide yes)
			(effects
				(font
					(size 1 1)
					(thickness 0.15)
				)
			)
		)
		(property "Public" "False"
			(at 0 0 90)
			(unlocked yes)
			(layer "F.Fab")
			(hide yes)
			(effects
				(font
					(size 1 1)
					(thickness 0.15)
				)
			)
		)
		(component_classes
			(class "DCDC_20V")
		)
		(sheetname "/DCDC/")
		(sheetfile "dcdc.kicad_sch")
		(attr smd)
		(fp_line
			(start -0.3 -0.7)
			(end 0.3 -0.7)
			(stroke
				(width 0.15)
				(type solid)
			)
			(layer "F.SilkS")
		)
		(fp_line
			(start -0.3 0.7)
			(end 0.3 0.7)
			(stroke
				(width 0.15)
				(type solid)
			)
			(layer "F.SilkS")
		)
		(fp_rect
			(start 1.95 -0.9)
			(end -1.95 0.9)
			(stroke
				(width 0.05)
				(type default)
			)
			(fill no)
			(layer "F.CrtYd")
		)
		(fp_rect
			(start -0.95 -0.675)
			(end 0.95 0.675)
			(stroke
				(width 0.15)
				(type solid)
			)
			(fill no)
			(layer "F.Fab")
		)
		(fp_text user "${REFERENCE}"
			(at -1.9 3.947 90)
			(layer "F.Fab")
			(effects
				(font
					(size 0.7 0.7)
					(thickness 0.15)
				)
				(justify left bottom)
			)
		)
		(fp_text user "License: Apache-2.0"
			(at -1.9 4.947 90)
			(layer "F.Fab")
			(effects
				(font
					(size 0.7 0.7)
					(thickness 0.15)
				)
				(justify left bottom)
			)
		)
		(fp_text user "Author: Antmicro"
			(at -1.9 5.947 90)
			(layer "F.Fab")
			(effects
				(font
					(size 0.7 0.7)
					(thickness 0.15)
				)
				(justify left bottom)
			)
		)
		(pad "1" smd roundrect
			(at -1.1 0 90)
			(size 1.2 1.3)
			(layers "F.Cu" "F.Mask" "F.Paste")
			(roundrect_rratio 0.25)
			(net 1 "GND")
			(pintype "passive")
		)
		(pad "2" smd roundrect
			(at 1.1 0 90)
			(size 1.2 1.3)
			(layers "F.Cu" "F.Mask" "F.Paste")
			(roundrect_rratio 0.25)
			(net 1105 "/DCDC/20V_OUT")
			(pintype "passive")
		)
	)
	(footprint "antmicro-footprints:Conn_Molex_PicoBlade_1x4_0533980471"
		(locked yes)
		(layer "F.Cu")
		(at 163.830532 144.9 -90)
		(descr "Molex PicoBlade series connector, 53398-0471")
		(tags "connector Molex PicoBlade side entry")
		(property "Reference" "J15"
			(at -6.8 -0.969468 180)
			(layer "F.SilkS")
			(effects
				(font
					(size 0.7 0.7)
					(thickness 0.15)
				)
				(justify right top)
			)
		)
		(property "Value" "Molex_PicoBlade_1x4_0533980471"
			(at -5.8 3.7 90)
			(layer "F.Fab")
			(effects
				(font
					(size 0.7 0.7)
					(thickness 0.15)
				)
				(justify right top)
			)
		)
		(property "Datasheet" "https://www.molex.com/molex/products/part-detail/pcb_headers/0533980471"
			(at 0 0 90)
			(layer "F.Fab")
			(hide yes)
			(effects
				(font
					(size 1.27 1.27)
					(thickness 0.15)
				)
			)
		)
		(property "Description" "Pin Header, Vertical, Signal, 1.25 mm, 1 Rows, 4 Contacts, Surface Mount Straight"
			(at 0 0 90)
			(layer "F.Fab")
			(hide yes)
			(effects
				(font
					(size 1.27 1.27)
					(thickness 0.15)
				)
			)
		)
		(property "MPN" "0533980471"
			(at 0 0 270)
			(unlocked yes)
			(layer "F.Fab")
			(hide yes)
			(effects
				(font
					(size 1 1)
					(thickness 0.15)
				)
			)
		)
		(property "Manufacturer" "Molex"
			(at 0 0 270)
			(unlocked yes)
			(layer "F.Fab")
			(hide yes)
			(effects
				(font
					(size 1 1)
					(thickness 0.15)
				)
			)
		)
		(property "Author" "Antmicro"
			(at 0 0 270)
			(unlocked yes)
			(layer "F.Fab")
			(hide yes)
			(effects
				(font
					(size 1 1)
					(thickness 0.15)
				)
			)
		)
		(property "License" "Apache-2.0"
			(at 0 0 270)
			(unlocked yes)
			(layer "F.Fab")
			(hide yes)
			(effects
				(font
					(size 1 1)
					(thickness 0.15)
				)
			)
		)
		(sheetname "/Peripherals/")
		(sheetfile "peripherals.kicad_sch")
		(attr smd)
		(fp_line
			(start -3.117 2.209)
			(end 3.115 2.209)
			(stroke
				(width 0.15)
				(type solid)
			)
			(layer "F.SilkS")
		)
		(fp_line
			(start -3.485 -0.76)
			(end -3.485 -1.71)
			(stroke
				(width 0.15)
				(type solid)
			)
			(layer "F.SilkS")
		)
		(fp_line
			(start 3.483 -0.76)
			(end 3.483 -1.71)
			(stroke
				(width 0.15)
				(type solid)
			)
			(layer "F.SilkS")
		)
		(fp_line
			(start -3.485 -1.71)
			(end -2.536 -1.71)
			(stroke
				(width 0.15)
				(type solid)
			)
			(layer "F.SilkS")
		)
		(fp_line
			(start -2.536 -1.71)
			(end -2.536 -2.4)
			(stroke
				(width 0.15)
				(type solid)
			)
			(layer "F.SilkS")
		)
		(fp_line
			(start 3.483 -1.71)
			(end 2.535 -1.71)
			(stroke
				(width 0.15)
				(type solid)
			)
			(layer "F.SilkS")
		)
		(fp_rect
			(start -5.677 -2.601)
			(end 5.675 2.7)
			(stroke
				(width 0.05)
				(type solid)
			)
			(fill no)
			(layer "F.CrtYd")
		)
		(fp_line
			(start -4.875 2.1)
			(end -5.077 1.898)
			(stroke
				(width 0.15)
				(type solid)
			)
			(layer "F.Fab")
		)
		(fp_line
			(start -3.375 2.1)
			(end -4.875 2.1)
			(stroke
				(width 0.15)
				(type solid)
			)
			(layer "F.Fab")
		)
		(fp_line
			(start -3.375 2.1)
			(end 3.374 2.1)
			(stroke
				(width 0.15)
				(type solid)
			)
			(layer "F.Fab")
		)
		(fp_line
			(start 3.374 2.1)
			(end 4.873 2.1)
			(stroke
				(width 0.15)
				(type solid)
			)
			(layer "F.Fab")
		)
		(fp_line
			(start 4.873 2.1)
			(end 5.075 1.898)
			(stroke
				(width 0.15)
				(type solid)
			)
			(layer "F.Fab")
		)
		(fp_line
			(start -5.077 1.898)
			(end -5.077 0.099)
			(stroke
				(width 0.15)
				(type solid)
			)
			(layer "F.Fab")
		)
		(fp_line
			(start 5.075 1.898)
			(end 5.075 0.099)
			(stroke
				(width 0.15)
				(type solid)
			)
			(layer "F.Fab")
		)
		(fp_line
			(start -2.025 1.175)
			(end -1.726 1.175)
			(stroke
				(width 0.15)
				(type solid)
			)
			(layer "F.Fab")
		)
		(fp_line
			(start -1.726 1.175)
			(end -1.726 0.575)
			(stroke
				(width 0.15)
				(type solid)
			)
			(layer "F.Fab")
		)
		(fp_line
			(start -0.777 1.175)
			(end -0.476 1.175)
			(stroke
				(width 0.15)
				(type solid)
			)
			(layer "F.Fab")
		)
		(fp_line
			(start -0.476 1.175)
			(end -0.476 0.575)
			(stroke
				(width 0.15)
				(type solid)
			)
			(layer "F.Fab")
		)
		(fp_line
			(start 0.474 1.175)
			(end 0.775 1.175)
			(stroke
				(width 0.15)
				(type solid)
			)
			(layer "F.Fab")
		)
		(fp_line
			(start 0.775 1.175)
			(end 0.775 0.575)
			(stroke
				(width 0.15)
				(type solid)
			)
			(layer "F.Fab")
		)
		(fp_line
			(start 1.725 1.175)
			(end 2.023 1.175)
			(stroke
				(width 0.15)
				(type solid)
			)
			(layer "F.Fab")
		)
		(fp_line
			(start 2.023 1.175)
			(end 2.023 0.575)
			(stroke
				(width 0.15)
				(type solid)
			)
			(layer "F.Fab")
		)
		(fp_line
			(start -2.025 0.575)
			(end -2.025 1.175)
			(stroke
				(width 0.15)
				(type solid)
			)
			(layer "F.Fab")
		)
		(fp_line
			(start -1.726 0.575)
			(end -2.025 0.575)
			(stroke
				(width 0.15)
				(type solid)
			)
			(layer "F.Fab")
		)
		(fp_line
			(start -0.777 0.575)
			(end -0.777 1.175)
			(stroke
				(width 0.15)
				(type solid)
			)
			(layer "F.Fab")
		)
		(fp_line
			(start -0.476 0.575)
			(end -0.777 0.575)
			(stroke
				(width 0.15)
				(type solid)
			)
			(layer "F.Fab")
		)
		(fp_line
			(start 0.474 0.575)
			(end 0.474 1.175)
			(stroke
				(width 0.15)
				(type solid)
			)
			(layer "F.Fab")
		)
		(fp_line
			(start 0.775 0.575)
			(end 0.474 0.575)
			(stroke
				(width 0.15)
				(type solid)
			)
			(layer "F.Fab")
		)
		(fp_line
			(start 1.725 0.575)
			(end 1.725 1.175)
			(stroke
				(width 0.15)
				(type solid)
			)
			(layer "F.Fab")
		)
		(fp_line
			(start 2.023 0.575)
			(end 1.725 0.575)
			(stroke
				(width 0.15)
				(type solid)
			)
			(layer "F.Fab")
		)
		(fp_line
			(start -5.077 0.099)
			(end -4.875 -0.101)
			(stroke
				(width 0.15)
				(type solid)
			)
			(layer "F.Fab")
		)
		(fp_line
			(start 5.075 0.099)
			(end 4.873 -0.101)
			(stroke
				(width 0.15)
				(type solid)
			)
			(layer "F.Fab")
		)
		(fp_line
			(start -4.875 -0.101)
			(end -4.875 -0.701)
			(stroke
				(width 0.15)
				(type solid)
			)
			(layer "F.Fab")
		)
		(fp_line
			(start 4.873 -0.101)
			(end 4.873 -0.701)
			(stroke
				(width 0.15)
				(type solid)
			)
			(layer "F.Fab")
		)
		(fp_line
			(start -4.875 -0.701)
			(end -3.375 -0.701)
			(stroke
				(width 0.15)
				(type solid)
			)
			(layer "F.Fab")
		)
		(fp_line
			(start 4.873 -0.701)
			(end 3.374 -0.701)
			(stroke
				(width 0.15)
				(type solid)
			)
			(layer "F.Fab")
		)
		(fp_line
			(start -1.875 -0.893)
			(end -1.375 -1.601)
			(stroke
				(width 0.15)
				(type solid)
			)
			(layer "F.Fab")
		)
		(fp_line
			(start -3.375 -1.601)
			(end -3.375 2.1)
			(stroke
				(width 0.15)
				(type solid)
			)
			(layer "F.Fab")
		)
		(fp_line
			(start -3.375 -1.601)
			(end 3.374 -1.601)
			(stroke
				(width 0.15)
				(type solid)
			)
			(layer "F.Fab")
		)
		(fp_line
			(start -2.375 -1.601)
			(end -1.875 -0.893)
			(stroke
				(width 0.15)
				(type solid)
			)
			(layer "F.Fab")
		)
		(fp_line
			(start 3.374 -1.601)
			(end 3.374 2.1)
			(stroke
				(width 0.15)
				(type solid)
			)
			(layer "F.Fab")
		)
		(fp_text user "${REFERENCE}"
			(at -5.8 5.2 90)
			(layer "F.Fab")
			(effects
				(font
					(size 0.7 0.7)
					(thickness 0.15)
				)
				(justify right top)
			)
		)
		(fp_text user "Author: Antmicro"
			(at -5.8 6.6 90)
			(layer "F.Fab")
			(effects
				(font
					(size 0.7 0.7)
					(thickness 0.15)
				)
				(justify right top)
			)
		)
		(fp_text user "License: Apache-2.0"
			(at -5.8 8 90)
			(layer "F.Fab")
			(effects
				(font
					(size 0.7 0.7)
					(thickness 0.15)
				)
				(justify right top)
			)
		)
		(pad "1" smd roundrect
			(at -1.875 -1.75 270)
			(size 0.8 1.3)
			(layers "F.Cu" "F.Mask" "F.Paste")
			(roundrect_rratio 0.25)
			(net 1 "GND")
			(pinfunction "1")
			(pintype "passive")
		)
		(pad "2" smd roundrect
			(at -0.625 -1.75 270)
			(size 0.8 1.3)
			(layers "F.Cu" "F.Mask" "F.Paste")
			(roundrect_rratio 0.25)
			(net 1043 "/Peripherals/FAN_VDD")
			(pinfunction "2")
			(pintype "passive")
		)
		(pad "3" smd roundrect
			(at 0.623 -1.75 270)
			(size 0.8 1.3)
			(layers "F.Cu" "F.Mask" "F.Paste")
			(roundrect_rratio 0.25)
			(net 279 "/Peripherals/FAN_TACH_5V")
			(pinfunction "3")
			(pintype "passive")
		)
		(pad "4" smd roundrect
			(at 1.874 -1.75 270)
			(size 0.8 1.3)
			(layers "F.Cu" "F.Mask" "F.Paste")
			(roundrect_rratio 0.25)
			(net 281 "/Peripherals/FAN_PWM_5V")
			(pinfunction "4")
			(pintype "passive")
		)
		(pad "MP1" smd roundrect
			(at -4.425 0.998 270)
			(size 2.1 3)
			(layers "F.Cu" "F.Mask" "F.Paste")
			(roundrect_rratio 0.119048)
			(net 1 "GND")
			(pinfunction "MP1")
			(pintype "passive")
		)
		(pad "MP2" smd roundrect
			(at 4.424 0.998 270)
			(size 2.1 3)
			(layers "F.Cu" "F.Mask" "F.Paste")
			(roundrect_rratio 0.119048)
			(net 1 "GND")
			(pinfunction "MP2")
			(pintype "passive")
		)
	)
)
